(kicad_pcb
	(version 20260206)
	(generator "pcbnew")
	(generator_version "10.0")
	(general
		(thickness 1.6)
		(legacy_teardrops no)
	)
	(paper "A4")
	(title_block
		(title "01162023_DA0F0TEBIF0_F0T_Expander_BD_F_brd_V02_OCP.brd")
		(comment 1 "Grand Teton / footprints 7712-7719 of 9728")
	)
	(layers
		(0 "F.Cu" signal "TOP")
		(4 "In1.Cu" signal "GND")
		(6 "In2.Cu" signal "VCC")
		(8 "In3.Cu" signal "VCC1")
		(10 "In4.Cu" signal "GND1")
		(12 "In5.Cu" signal "IN1")
		(14 "In6.Cu" signal "GND2")
		(16 "In7.Cu" signal "IN2")
		(18 "In8.Cu" signal "GND3")
		(20 "In9.Cu" signal "IN3")
		(22 "In10.Cu" signal "GND4")
		(24 "In11.Cu" signal "IN4")
		(26 "In12.Cu" signal "GND5")
		(28 "In13.Cu" signal "IN5")
		(30 "In14.Cu" signal "GND6")
		(32 "In15.Cu" signal "IN6")
		(34 "In16.Cu" signal "GND7")
		(2 "B.Cu" signal "BOTTOM")
		(9 "F.Adhes" user "F.Adhesive")
		(11 "B.Adhes" user "B.Adhesive")
		(13 "F.Paste" user "Package Geometry/Pastemask Top")
		(15 "B.Paste" user "Package Geometry/Pastemask Bottom")
		(5 "F.SilkS" user "Ref Des/Silkscreen Top")
		(7 "B.SilkS" user "Ref Des/Silkscreen Bottom")
		(1 "F.Mask" user "Board Geometry/Soldermask Top")
		(3 "B.Mask" user "Board Geometry/Soldermask Bottom")
		(17 "Dwgs.User" user "User.Drawings")
		(19 "Cmts.User" user "User.Comments")
		(21 "Eco1.User" user "User.Eco1")
		(23 "Eco2.User" user "User.Eco2")
		(25 "Edge.Cuts" user "Board Geometry/Outline")
		(27 "Margin" user)
		(31 "F.CrtYd" user "Package Geometry/Place Bound Top")
		(29 "B.CrtYd" user "Package Geometry/Place Bound Bottom")
		(35 "F.Fab" user "Ref Des/Assembly Top")
		(33 "B.Fab" user "Ref Des/Assembly Bottom")
	)
	(footprint ""
		(layer "B.Cu")
		(at 109.543088 -352.812604)
		(property "Reference" "R6380"
			(at 0 0 0)
			(layer "B.SilkS")
			(hide yes)
			(effects
				(font
					(size 1.27 1.27)
				)
				(justify mirror)
			)
		)
		(property "Value" ""
			(at 0 0 0)
			(layer "B.Fab")
			(effects
				(font
					(size 1.27 1.27)
				)
				(justify mirror)
			)
		)
		(duplicate_pad_numbers_are_jumpers no)
		(fp_line
			(start -0.7874 -0.4064)
			(end -0.7874 0.4064)
			(stroke
				(width 0.1524)
				(type default)
			)
			(layer "B.SilkS")
		)
		(fp_line
			(start -0.7874 0.4064)
			(end 0.7874 0.4064)
			(stroke
				(width 0.1524)
				(type default)
			)
			(layer "B.SilkS")
		)
		(fp_line
			(start 0.7874 -0.4064)
			(end -0.7874 -0.4064)
			(stroke
				(width 0.1524)
				(type default)
			)
			(layer "B.SilkS")
		)
		(fp_line
			(start 0.7874 0.4064)
			(end 0.7874 -0.4064)
			(stroke
				(width 0.1524)
				(type default)
			)
			(layer "B.SilkS")
		)
		(fp_line
			(start -0.67945 -0.3048)
			(end -0.67945 0.3048)
			(stroke
				(width 0.1)
				(type default)
			)
			(layer "B.Fab")
		)
		(fp_line
			(start -0.67945 0.3048)
			(end -0.120396 0.3048)
			(stroke
				(width 0.1)
				(type default)
			)
			(layer "B.Fab")
		)
		(fp_line
			(start -0.12065 -0.3048)
			(end -0.67945 -0.3048)
			(stroke
				(width 0.1)
				(type default)
			)
			(layer "B.Fab")
		)
		(fp_line
			(start -0.12065 -0.2794)
			(end -0.12065 -0.3048)
			(stroke
				(width 0.1)
				(type default)
			)
			(layer "B.Fab")
		)
		(fp_line
			(start -0.120396 0.2794)
			(end 0.12065 0.2794)
			(stroke
				(width 0.1)
				(type default)
			)
			(layer "B.Fab")
		)
		(fp_line
			(start -0.120396 0.3048)
			(end -0.120396 0.2794)
			(stroke
				(width 0.1)
				(type default)
			)
			(layer "B.Fab")
		)
		(fp_line
			(start 0.12065 -0.305054)
			(end 0.12065 -0.2794)
			(stroke
				(width 0.1)
				(type default)
			)
			(layer "B.Fab")
		)
		(fp_line
			(start 0.12065 -0.2794)
			(end -0.12065 -0.2794)
			(stroke
				(width 0.1)
				(type default)
			)
			(layer "B.Fab")
		)
		(fp_line
			(start 0.12065 0.2794)
			(end 0.12065 0.3048)
			(stroke
				(width 0.1)
				(type default)
			)
			(layer "B.Fab")
		)
		(fp_line
			(start 0.12065 0.3048)
			(end 0.67945 0.3048)
			(stroke
				(width 0.1)
				(type default)
			)
			(layer "B.Fab")
		)
		(fp_line
			(start 0.67945 -0.305054)
			(end 0.12065 -0.305054)
			(stroke
				(width 0.1)
				(type default)
			)
			(layer "B.Fab")
		)
		(fp_line
			(start 0.67945 0.3048)
			(end 0.67945 -0.305054)
			(stroke
				(width 0.1)
				(type default)
			)
			(layer "B.Fab")
		)
		(pad "1" smd circle
			(at 0.40005 0 180)
			(size 0 0)
			(layers "B.Cu" "B.Mask" "B.Paste")
			(net "CLK_100M_DB800ZL_PEX3_S3_R_DP")
		)
		(pad "2" smd circle
			(at -0.40005 0 180)
			(size 0 0)
			(layers "B.Cu" "B.Mask" "B.Paste")
			(net "CLK_100M_DB800ZL_PEX3_S3_DP")
		)
	)
	(footprint ""
		(layer "B.Cu")
		(at 411.750002 -301.599854 -90)
		(property "Reference" "C1980"
			(at 0 0 90)
			(layer "B.SilkS")
			(hide yes)
			(effects
				(font
					(size 1.27 1.27)
				)
				(justify mirror)
			)
		)
		(property "Value" ""
			(at 0 0 90)
			(layer "B.Fab")
			(effects
				(font
					(size 1.27 1.27)
				)
				(justify mirror)
			)
		)
		(duplicate_pad_numbers_are_jumpers no)
		(fp_line
			(start -0.299974 0.150114)
			(end 0.299974 0.150114)
			(stroke
				(width 0.1)
				(type default)
			)
			(layer "B.Fab")
		)
		(fp_line
			(start 0.299974 0.150114)
			(end 0.299974 -0.150114)
			(stroke
				(width 0.1)
				(type default)
			)
			(layer "B.Fab")
		)
		(fp_line
			(start -0.299974 -0.150114)
			(end -0.299974 0.150114)
			(stroke
				(width 0.1)
				(type default)
			)
			(layer "B.Fab")
		)
		(fp_line
			(start 0.299974 -0.150114)
			(end -0.299974 -0.150114)
			(stroke
				(width 0.1)
				(type default)
			)
			(layer "B.Fab")
		)
		(pad "1" smd rect
			(at 0.2667 0 90)
			(size 0.3048 0.381)
			(layers "B.Cu" "B.Mask" "B.Paste")
			(net "P0V8_SERDES_VDDA_PEX3")
		)
		(pad "2" smd rect
			(at -0.2667 0 90)
			(size 0.3048 0.381)
			(layers "B.Cu" "B.Mask" "B.Paste")
			(net "GND")
		)
	)
	(footprint ""
		(layer "B.Cu")
		(at 168.150032 -288.299906 90)
		(property "Reference" "C3098"
			(at 0 0 90)
			(layer "B.SilkS")
			(hide yes)
			(effects
				(font
					(size 1.27 1.27)
				)
				(justify mirror)
			)
		)
		(property "Value" ""
			(at 0 0 90)
			(layer "B.Fab")
			(effects
				(font
					(size 1.27 1.27)
				)
				(justify mirror)
			)
		)
		(duplicate_pad_numbers_are_jumpers no)
		(fp_line
			(start 0.299974 -0.150114)
			(end -0.299974 -0.150114)
			(stroke
				(width 0.1)
				(type default)
			)
			(layer "B.Fab")
		)
		(fp_line
			(start -0.299974 -0.150114)
			(end -0.299974 0.150114)
			(stroke
				(width 0.1)
				(type default)
			)
			(layer "B.Fab")
		)
		(fp_line
			(start 0.299974 0.150114)
			(end 0.299974 -0.150114)
			(stroke
				(width 0.1)
				(type default)
			)
			(layer "B.Fab")
		)
		(fp_line
			(start -0.299974 0.150114)
			(end 0.299974 0.150114)
			(stroke
				(width 0.1)
				(type default)
			)
			(layer "B.Fab")
		)
		(pad "1" smd rect
			(at 0.2667 0 270)
			(size 0.3048 0.381)
			(layers "B.Cu" "B.Mask" "B.Paste")
			(net "P1V25_PEX1")
		)
		(pad "2" smd rect
			(at -0.2667 0 270)
			(size 0.3048 0.381)
			(layers "B.Cu" "B.Mask" "B.Paste")
			(net "GND")
		)
	)
	(footprint ""
		(layer "B.Cu")
		(at 330.729336 -219.452952 180)
		(property "Reference" "R5640"
			(at 0 0 0)
			(layer "B.SilkS")
			(hide yes)
			(effects
				(font
					(size 1.27 1.27)
				)
				(justify mirror)
			)
		)
		(property "Value" ""
			(at 0 0 0)
			(layer "B.Fab")
			(effects
				(font
					(size 1.27 1.27)
				)
				(justify mirror)
			)
		)
		(duplicate_pad_numbers_are_jumpers no)
		(fp_line
			(start 1.2954 0.5842)
			(end 1.2954 -0.5842)
			(stroke
				(width 0.1524)
				(type default)
			)
			(layer "B.SilkS")
		)
		(fp_line
			(start 1.2954 -0.5842)
			(end -1.2954 -0.5842)
			(stroke
				(width 0.1524)
				(type default)
			)
			(layer "B.SilkS")
		)
		(fp_line
			(start -1.2954 0.5842)
			(end 1.2954 0.5842)
			(stroke
				(width 0.1524)
				(type default)
			)
			(layer "B.SilkS")
		)
		(fp_line
			(start -1.2954 -0.5842)
			(end -1.2954 0.5842)
			(stroke
				(width 0.1524)
				(type default)
			)
			(layer "B.SilkS")
		)
		(fp_line
			(start 1.1938 0.4064)
			(end 1.1938 -0.406654)
			(stroke
				(width 0.1)
				(type default)
			)
			(layer "B.Fab")
		)
		(fp_line
			(start 1.1938 -0.406654)
			(end 0.8636 -0.406654)
			(stroke
				(width 0.1)
				(type default)
			)
			(layer "B.Fab")
		)
		(fp_line
			(start 0.8636 0.4572)
			(end 0.8636 0.4318)
			(stroke
				(width 0.1)
				(type default)
			)
			(layer "B.Fab")
		)
		(fp_line
			(start 0.8636 0.4318)
			(end 0.8636 0.4064)
			(stroke
				(width 0.1)
				(type default)
			)
			(layer "B.Fab")
		)
		(fp_line
			(start 0.8636 0.4064)
			(end 1.1938 0.4064)
			(stroke
				(width 0.1)
				(type default)
			)
			(layer "B.Fab")
		)
		(fp_line
			(start 0.8636 -0.406654)
			(end 0.8636 -0.4572)
			(stroke
				(width 0.1)
				(type default)
			)
			(layer "B.Fab")
		)
		(fp_line
			(start 0.8636 -0.4572)
			(end -0.8636 -0.4572)
			(stroke
				(width 0.1)
				(type default)
			)
			(layer "B.Fab")
		)
		(fp_line
			(start -0.8636 0.4572)
			(end 0.8636 0.4572)
			(stroke
				(width 0.1)
				(type default)
			)
			(layer "B.Fab")
		)
		(fp_line
			(start -0.8636 0.4064)
			(end -0.8636 0.4572)
			(stroke
				(width 0.1)
				(type default)
			)
			(layer "B.Fab")
		)
		(fp_line
			(start -0.8636 -0.406654)
			(end -1.1938 -0.406654)
			(stroke
				(width 0.1)
				(type default)
			)
			(layer "B.Fab")
		)
		(fp_line
			(start -0.8636 -0.4572)
			(end -0.8636 -0.406654)
			(stroke
				(width 0.1)
				(type default)
			)
			(layer "B.Fab")
		)
		(fp_line
			(start -1.1938 0.4064)
			(end -0.8636 0.4064)
			(stroke
				(width 0.1)
				(type default)
			)
			(layer "B.Fab")
		)
		(fp_line
			(start -1.1938 -0.406654)
			(end -1.1938 0.4064)
			(stroke
				(width 0.1)
				(type default)
			)
			(layer "B.Fab")
		)
		(pad "1" smd rect
			(at 0.7366 0 90)
			(size 0.7112 0.8128)
			(layers "B.Cu" "B.Mask" "B.Paste")
			(net "P3V3_AUX")
		)
		(pad "2" smd rect
			(at -0.7366 0 90)
			(size 0.7112 0.8128)
			(layers "B.Cu" "B.Mask" "B.Paste")
			(net "P3V3_FPGA_VCCIO4")
		)
	)
	(footprint ""
		(layer "B.Cu")
		(at 56.799988 -288.299906 90)
		(property "Reference" "C2942"
			(at 0 0 90)
			(layer "B.SilkS")
			(hide yes)
			(effects
				(font
					(size 1.27 1.27)
				)
				(justify mirror)
			)
		)
		(property "Value" ""
			(at 0 0 90)
			(layer "B.Fab")
			(effects
				(font
					(size 1.27 1.27)
				)
				(justify mirror)
			)
		)
		(duplicate_pad_numbers_are_jumpers no)
		(fp_line
			(start 0.299974 -0.150114)
			(end -0.299974 -0.150114)
			(stroke
				(width 0.1)
				(type default)
			)
			(layer "B.Fab")
		)
		(fp_line
			(start -0.299974 -0.150114)
			(end -0.299974 0.150114)
			(stroke
				(width 0.1)
				(type default)
			)
			(layer "B.Fab")
		)
		(fp_line
			(start 0.299974 0.150114)
			(end 0.299974 -0.150114)
			(stroke
				(width 0.1)
				(type default)
			)
			(layer "B.Fab")
		)
		(fp_line
			(start -0.299974 0.150114)
			(end 0.299974 0.150114)
			(stroke
				(width 0.1)
				(type default)
			)
			(layer "B.Fab")
		)
		(pad "1" smd rect
			(at 0.2667 0 270)
			(size 0.3048 0.381)
			(layers "B.Cu" "B.Mask" "B.Paste")
			(net "P1V25_PEX0")
		)
		(pad "2" smd rect
			(at -0.2667 0 270)
			(size 0.3048 0.381)
			(layers "B.Cu" "B.Mask" "B.Paste")
			(net "GND")
		)
	)
	(footprint ""
		(layer "B.Cu")
		(at 117.06479 -255.86055 180)
		(property "Reference" "PC44"
			(at 0 0 0)
			(layer "B.SilkS")
			(hide yes)
			(effects
				(font
					(size 1.27 1.27)
				)
				(justify mirror)
			)
		)
		(property "Value" ""
			(at 0 0 0)
			(layer "B.Fab")
			(effects
				(font
					(size 1.27 1.27)
				)
				(justify mirror)
			)
		)
		(duplicate_pad_numbers_are_jumpers no)
		(fp_line
			(start 0.7874 0.4064)
			(end 0.7874 -0.4064)
			(stroke
				(width 0.1524)
				(type default)
			)
			(layer "B.SilkS")
		)
		(fp_line
			(start 0.7874 -0.4064)
			(end -0.7874 -0.4064)
			(stroke
				(width 0.1524)
				(type default)
			)
			(layer "B.SilkS")
		)
		(fp_line
			(start -0.7874 0.4064)
			(end 0.7874 0.4064)
			(stroke
				(width 0.1524)
				(type default)
			)
			(layer "B.SilkS")
		)
		(fp_line
			(start -0.7874 -0.4064)
			(end -0.7874 0.4064)
			(stroke
				(width 0.1524)
				(type default)
			)
			(layer "B.SilkS")
		)
		(fp_line
			(start 0.67945 0.3048)
			(end 0.67945 -0.305054)
			(stroke
				(width 0.1)
				(type default)
			)
			(layer "B.Fab")
		)
		(fp_line
			(start 0.67945 -0.305054)
			(end 0.12065 -0.305054)
			(stroke
				(width 0.1)
				(type default)
			)
			(layer "B.Fab")
		)
		(fp_line
			(start 0.12065 0.3048)
			(end 0.67945 0.3048)
			(stroke
				(width 0.1)
				(type default)
			)
			(layer "B.Fab")
		)
		(fp_line
			(start 0.12065 0.2794)
			(end 0.12065 0.3048)
			(stroke
				(width 0.1)
				(type default)
			)
			(layer "B.Fab")
		)
		(fp_line
			(start 0.12065 -0.2794)
			(end -0.12065 -0.2794)
			(stroke
				(width 0.1)
				(type default)
			)
			(layer "B.Fab")
		)
		(fp_line
			(start 0.12065 -0.305054)
			(end 0.12065 -0.2794)
			(stroke
				(width 0.1)
				(type default)
			)
			(layer "B.Fab")
		)
		(fp_line
			(start -0.120396 0.3048)
			(end -0.120396 0.2794)
			(stroke
				(width 0.1)
				(type default)
			)
			(layer "B.Fab")
		)
		(fp_line
			(start -0.120396 0.2794)
			(end 0.12065 0.2794)
			(stroke
				(width 0.1)
				(type default)
			)
			(layer "B.Fab")
		)
		(fp_line
			(start -0.12065 -0.2794)
			(end -0.12065 -0.3048)
			(stroke
				(width 0.1)
				(type default)
			)
			(layer "B.Fab")
		)
		(fp_line
			(start -0.12065 -0.3048)
			(end -0.67945 -0.3048)
			(stroke
				(width 0.1)
				(type default)
			)
			(layer "B.Fab")
		)
		(fp_line
			(start -0.67945 0.3048)
			(end -0.120396 0.3048)
			(stroke
				(width 0.1)
				(type default)
			)
			(layer "B.Fab")
		)
		(fp_line
			(start -0.67945 -0.3048)
			(end -0.67945 0.3048)
			(stroke
				(width 0.1)
				(type default)
			)
			(layer "B.Fab")
		)
		(pad "1" smd circle
			(at 0.40005 0)
			(size 0 0)
			(layers "B.Cu" "B.Mask" "B.Paste")
			(net "P0V8_PEX0_VDD")
		)
		(pad "2" smd circle
			(at -0.40005 0)
			(size 0 0)
			(layers "B.Cu" "B.Mask" "B.Paste")
			(net "GND")
		)
	)
	(footprint ""
		(layer "B.Cu")
		(at 346.65031 -258.004564 -90)
		(property "Reference" "PC134"
			(at 0 0 90)
			(layer "B.SilkS")
			(hide yes)
			(effects
				(font
					(size 1.27 1.27)
				)
				(justify mirror)
			)
		)
		(property "Value" ""
			(at 0 0 90)
			(layer "B.Fab")
			(effects
				(font
					(size 1.27 1.27)
				)
				(justify mirror)
			)
		)
		(duplicate_pad_numbers_are_jumpers no)
		(fp_line
			(start -0.7874 0.4064)
			(end 0.7874 0.4064)
			(stroke
				(width 0.1524)
				(type default)
			)
			(layer "B.SilkS")
		)
		(fp_line
			(start 0.7874 0.4064)
			(end 0.7874 -0.4064)
			(stroke
				(width 0.1524)
				(type default)
			)
			(layer "B.SilkS")
		)
		(fp_line
			(start -0.7874 -0.4064)
			(end -0.7874 0.4064)
			(stroke
				(width 0.1524)
				(type default)
			)
			(layer "B.SilkS")
		)
		(fp_line
			(start 0.7874 -0.4064)
			(end -0.7874 -0.4064)
			(stroke
				(width 0.1524)
				(type default)
			)
			(layer "B.SilkS")
		)
		(fp_line
			(start -0.67945 0.3048)
			(end -0.120396 0.3048)
			(stroke
				(width 0.1)
				(type default)
			)
			(layer "B.Fab")
		)
		(fp_line
			(start -0.120396 0.3048)
			(end -0.120396 0.2794)
			(stroke
				(width 0.1)
				(type default)
			)
			(layer "B.Fab")
		)
		(fp_line
			(start 0.12065 0.3048)
			(end 0.67945 0.3048)
			(stroke
				(width 0.1)
				(type default)
			)
			(layer "B.Fab")
		)
		(fp_line
			(start 0.67945 0.3048)
			(end 0.67945 -0.305054)
			(stroke
				(width 0.1)
				(type default)
			)
			(layer "B.Fab")
		)
		(fp_line
			(start -0.120396 0.2794)
			(end 0.12065 0.2794)
			(stroke
				(width 0.1)
				(type default)
			)
			(layer "B.Fab")
		)
		(fp_line
			(start 0.12065 0.2794)
			(end 0.12065 0.3048)
			(stroke
				(width 0.1)
				(type default)
			)
			(layer "B.Fab")
		)
		(fp_line
			(start -0.12065 -0.2794)
			(end -0.12065 -0.3048)
			(stroke
				(width 0.1)
				(type default)
			)
			(layer "B.Fab")
		)
		(fp_line
			(start 0.12065 -0.2794)
			(end -0.12065 -0.2794)
			(stroke
				(width 0.1)
				(type default)
			)
			(layer "B.Fab")
		)
		(fp_line
			(start -0.67945 -0.3048)
			(end -0.67945 0.3048)
			(stroke
				(width 0.1)
				(type default)
			)
			(layer "B.Fab")
		)
		(fp_line
			(start -0.12065 -0.3048)
			(end -0.67945 -0.3048)
			(stroke
				(width 0.1)
				(type default)
			)
			(layer "B.Fab")
		)
		(fp_line
			(start 0.12065 -0.305054)
			(end 0.12065 -0.2794)
			(stroke
				(width 0.1)
				(type default)
			)
			(layer "B.Fab")
		)
		(fp_line
			(start 0.67945 -0.305054)
			(end 0.12065 -0.305054)
			(stroke
				(width 0.1)
				(type default)
			)
			(layer "B.Fab")
		)
		(pad "1" smd circle
			(at 0.40005 0 90)
			(size 0 0)
			(layers "B.Cu" "B.Mask" "B.Paste")
			(net "P0V8_PEX2_IINSEN")
		)
		(pad "2" smd circle
			(at -0.40005 0 90)
			(size 0 0)
			(layers "B.Cu" "B.Mask" "B.Paste")
			(net "GND")
		)
	)
	(footprint ""
		(layer "B.Cu")
		(at 424.02379 -291.624766 90)
		(property "Reference" "R998"
			(at 0 0 90)
			(layer "B.SilkS")
			(hide yes)
			(effects
				(font
					(size 1.27 1.27)
				)
				(justify mirror)
			)
		)
		(property "Value" ""
			(at 0 0 90)
			(layer "B.Fab")
			(effects
				(font
					(size 1.27 1.27)
				)
				(justify mirror)
			)
		)
		(duplicate_pad_numbers_are_jumpers no)
		(fp_line
			(start 0.7874 -0.4064)
			(end -0.7874 -0.4064)
			(stroke
				(width 0.1524)
				(type default)
			)
			(layer "B.SilkS")
		)
		(fp_line
			(start -0.7874 -0.4064)
			(end -0.7874 0.4064)
			(stroke
				(width 0.1524)
				(type default)
			)
			(layer "B.SilkS")
		)
		(fp_line
			(start 0.7874 0.4064)
			(end 0.7874 -0.4064)
			(stroke
				(width 0.1524)
				(type default)
			)
			(layer "B.SilkS")
		)
		(fp_line
			(start -0.7874 0.4064)
			(end 0.7874 0.4064)
			(stroke
				(width 0.1524)
				(type default)
			)
			(layer "B.SilkS")
		)
		(fp_line
			(start 0.67945 -0.305054)
			(end 0.12065 -0.305054)
			(stroke
				(width 0.1)
				(type default)
			)
			(layer "B.Fab")
		)
		(fp_line
			(start 0.12065 -0.305054)
			(end 0.12065 -0.2794)
			(stroke
				(width 0.1)
				(type default)
			)
			(layer "B.Fab")
		)
		(fp_line
			(start -0.12065 -0.3048)
			(end -0.67945 -0.3048)
			(stroke
				(width 0.1)
				(type default)
			)
			(layer "B.Fab")
		)
		(fp_line
			(start -0.67945 -0.3048)
			(end -0.67945 0.3048)
			(stroke
				(width 0.1)
				(type default)
			)
			(layer "B.Fab")
		)
		(fp_line
			(start 0.12065 -0.2794)
			(end -0.12065 -0.2794)
			(stroke
				(width 0.1)
				(type default)
			)
			(layer "B.Fab")
		)
		(fp_line
			(start -0.12065 -0.2794)
			(end -0.12065 -0.3048)
			(stroke
				(width 0.1)
				(type default)
			)
			(layer "B.Fab")
		)
		(fp_line
			(start 0.12065 0.2794)
			(end 0.12065 0.3048)
			(stroke
				(width 0.1)
				(type default)
			)
			(layer "B.Fab")
		)
		(fp_line
			(start -0.120396 0.2794)
			(end 0.12065 0.2794)
			(stroke
				(width 0.1)
				(type default)
			)
			(layer "B.Fab")
		)
		(fp_line
			(start 0.67945 0.3048)
			(end 0.67945 -0.305054)
			(stroke
				(width 0.1)
				(type default)
			)
			(layer "B.Fab")
		)
		(fp_line
			(start 0.12065 0.3048)
			(end 0.67945 0.3048)
			(stroke
				(width 0.1)
				(type default)
			)
			(layer "B.Fab")
		)
		(fp_line
			(start -0.120396 0.3048)
			(end -0.120396 0.2794)
			(stroke
				(width 0.1)
				(type default)
			)
			(layer "B.Fab")
		)
		(fp_line
			(start -0.67945 0.3048)
			(end -0.120396 0.3048)
			(stroke
				(width 0.1)
				(type default)
			)
			(layer "B.Fab")
		)
		(pad "1" smd circle
			(at 0.40005 0 270)
			(size 0 0)
			(layers "B.Cu" "B.Mask" "B.Paste")
			(net "UART_PEX3_CLI_TX")
		)
		(pad "2" smd circle
			(at -0.40005 0 270)
			(size 0 0)
			(layers "B.Cu" "B.Mask" "B.Paste")
			(net "UART_PEX3_CLI_R_TX")
		)
	)
)
